FILE_TYPE = MACRO_DRAWING;
SET COLOR_WIRE YELLOW;
SET COLOR_PROP ORANGE;
SET COLOR_DOT WHITE;
SET COLOR_ARC YELLOW;
SET COLOR_BODY GREEN;
SET COLOR_NOTE PURPLE;
SET PROP_DISPLAY VALUE;
SET PAGE_NUMBER P274;
FORCEADD Q_CAP..1
(-1725 0);
FORCEPROP 1 LAST LOCATION C1562
J 0
(-1675 100);
DISPLAY 0.978723 (-1675 100);
FORCEPROP 0 LAST $SEC 1
J 0
(-1675 150);
DISPLAY 0.680851 (-1675 150);
PAINT MONO (-1675 150);
DISPLAY INVISIBLE (-1675 150);
FORCEPROP 0 LAST CDS_SEC 1
J 0
(-1675 150);
DISPLAY 1.021277 (-1675 150);
DISPLAY INVISIBLE (-1675 150);
FORCEPROP 1 LASTPIN (-1725 100) $PN 1
J 0
(-1715 80);
DISPLAY 0.787234 (-1715 80);
PAINT MONO (-1715 80);
FORCEPROP 1 LASTPIN (-1725 -100) $PN 2
J 0
(-1715 -120);
DISPLAY 0.787234 (-1715 -120);
PAINT MONO (-1715 -120);
FORCEPROP 1 LAST PACK_TYPE 0402
J 0
(-1675 -200);
DISPLAY 0.510638 (-1675 -200);
FORCEPROP 1 LAST VOLTAGE 25V
J 0
(-1675 0);
DISPLAY 0.510638 (-1675 0);
FORCEPROP 1 LAST VALUE 0.1UF
J 0
(-1675 50);
DISPLAY 0.510638 (-1675 50);
FORCEPROP 1 LAST PART_NUMBER CH4104K1B00
J 0
(-1675 -150);
DISPLAY 0.510638 (-1675 -150);
FORCEPROP 1 LAST MATERIAL X7R
J 0
(-1675 -100);
DISPLAY 0.510638 (-1675 -100);
FORCEPROP 1 LAST TOLERANCE 10%
J 0
(-1675 -50);
DISPLAY 0.510638 (-1675 -50);
FORCEPROP 1 LAST PATH I103
J 0
(-1675 150);
DISPLAY 0.978723 (-1675 150);
PAINT WHITE (-1675 150);
DISPLAY INVISIBLE (-1675 150);
FORCEPROP 2 LAST CDS_LIB pure_quanta
J 0
(-1725 0);
DISPLAY INVISIBLE (-1725 0);
FORCEADD Q_CAP..1
(-1325 2200);
FORCEPROP 1 LAST LOCATION C1561
J 0
(-1275 2300);
DISPLAY 0.978723 (-1275 2300);
FORCEPROP 0 LAST $SEC 1
J 0
(-1275 2350);
DISPLAY 0.680851 (-1275 2350);
PAINT MONO (-1275 2350);
DISPLAY INVISIBLE (-1275 2350);
FORCEPROP 0 LAST CDS_SEC 1
J 0
(-1275 2350);
DISPLAY 1.021277 (-1275 2350);
DISPLAY INVISIBLE (-1275 2350);
FORCEPROP 1 LASTPIN (-1325 2300) $PN 1
J 0
(-1315 2280);
DISPLAY 0.787234 (-1315 2280);
PAINT MONO (-1315 2280);
FORCEPROP 1 LASTPIN (-1325 2100) $PN 2
J 0
(-1315 2080);
DISPLAY 0.787234 (-1315 2080);
PAINT MONO (-1315 2080);
FORCEPROP 1 LAST PACK_TYPE 0402
J 0
(-1275 2000);
DISPLAY 0.510638 (-1275 2000);
FORCEPROP 1 LAST MATERIAL X7R
J 0
(-1275 2100);
DISPLAY 0.510638 (-1275 2100);
FORCEPROP 1 LAST TOLERANCE 10%
J 0
(-1275 2150);
DISPLAY 0.510638 (-1275 2150);
FORCEPROP 1 LAST VOLTAGE 25V
J 0
(-1275 2200);
DISPLAY 0.510638 (-1275 2200);
FORCEPROP 1 LAST VALUE 0.1UF
J 0
(-1275 2250);
DISPLAY 0.510638 (-1275 2250);
FORCEPROP 1 LAST PART_NUMBER CH4104K1B00
J 0
(-1275 2050);
DISPLAY 0.510638 (-1275 2050);
FORCEPROP 2 LAST CDS_LIB pure_quanta
J 0
(-1325 2200);
DISPLAY INVISIBLE (-1325 2200);
FORCEPROP 1 LAST PATH I104
J 0
(-1275 2350);
DISPLAY 0.978723 (-1275 2350);
PAINT WHITE (-1275 2350);
DISPLAY INVISIBLE (-1275 2350);
FORCEADD UNIVERSAL_GND..1
(-2500 -500);
FORCEPROP 3 LASTPIN (-2500 -450) SIG_NAME GND\g
J 0
(-2490 -440);
DISPLAY 0.659574 (-2490 -440);
PAINT MONO (-2490 -440);
DISPLAY INVISIBLE (-2490 -440);
FORCEPROP 1 LAST HDL_POWER GND
J 1
(-2475 -575);
DISPLAY 0.872340 (-2475 -575);
PAINT GREEN (-2475 -575);
DISPLAY INVISIBLE (-2475 -575);
FORCEPROP 1 LAST PATH I105
J 0
(-2425 -500);
DISPLAY 0.872340 (-2425 -500);
PAINT AQUA (-2425 -500);
DISPLAY INVISIBLE (-2425 -500);
FORCEPROP 2 LAST CDS_LIB pure_quanta_power
J 0
(-2500 -500);
DISPLAY INVISIBLE (-2500 -500);
FORCEADD UNIVERSAL_GND..1
(-2625 1150);
FORCEPROP 3 LASTPIN (-2625 1200) SIG_NAME GND\g
J 0
(-2615 1210);
DISPLAY 0.659574 (-2615 1210);
PAINT MONO (-2615 1210);
DISPLAY INVISIBLE (-2615 1210);
FORCEPROP 2 LAST CDS_LIB pure_quanta_power
J 0
(-2625 1150);
DISPLAY INVISIBLE (-2625 1150);
FORCEPROP 1 LAST PATH I106
J 0
(-2550 1150);
DISPLAY 0.872340 (-2550 1150);
PAINT AQUA (-2550 1150);
DISPLAY INVISIBLE (-2550 1150);
FORCEPROP 1 LAST HDL_POWER GND
J 1
(-2600 1075);
DISPLAY 0.872340 (-2600 1075);
PAINT GREEN (-2600 1075);
DISPLAY INVISIBLE (-2600 1075);
FORCEADD UNIVERSAL_GND..1
(-2025 1150);
FORCEPROP 3 LASTPIN (-2025 1200) SIG_NAME GND\g
J 0
(-2015 1210);
DISPLAY 0.659574 (-2015 1210);
PAINT MONO (-2015 1210);
DISPLAY INVISIBLE (-2015 1210);
FORCEPROP 1 LAST HDL_POWER GND
J 1
(-2000 1075);
DISPLAY 0.872340 (-2000 1075);
PAINT GREEN (-2000 1075);
DISPLAY INVISIBLE (-2000 1075);
FORCEPROP 1 LAST PATH I107
J 0
(-1950 1150);
DISPLAY 0.872340 (-1950 1150);
PAINT AQUA (-1950 1150);
DISPLAY INVISIBLE (-1950 1150);
FORCEPROP 2 LAST CDS_LIB pure_quanta_power
J 0
(-2025 1150);
DISPLAY INVISIBLE (-2025 1150);
FORCEADD UNIVERSAL_GND..1
(-1325 1950);
FORCEPROP 3 LASTPIN (-1325 2000) SIG_NAME GND\g
J 0
(-1315 2010);
DISPLAY 0.659574 (-1315 2010);
PAINT MONO (-1315 2010);
DISPLAY INVISIBLE (-1315 2010);
FORCEPROP 2 LAST CDS_LIB pure_quanta_power
J 0
(-1325 1950);
DISPLAY INVISIBLE (-1325 1950);
FORCEPROP 1 LAST PATH I108
J 0
(-1250 1950);
DISPLAY 0.872340 (-1250 1950);
PAINT AQUA (-1250 1950);
DISPLAY INVISIBLE (-1250 1950);
FORCEPROP 1 LAST HDL_POWER GND
J 1
(-1300 1875);
DISPLAY 0.872340 (-1300 1875);
PAINT GREEN (-1300 1875);
DISPLAY INVISIBLE (-1300 1875);
FORCEADD MOSFET_N..1
(1900 1800);
FORCEPROP 1 LAST $LOCATION U325
J 0
(2072 1491);
DISPLAY 0.723404 (2072 1491);
PAINT GREEN (2072 1491);
FORCEPROP 0 LAST CDS_LOCATION U325
J 0
(2075 1725);
DISPLAY 1.021277 (2075 1725);
DISPLAY INVISIBLE (2075 1725);
FORCEPROP 0 LAST $SEC 1
J 0
(2075 1725);
DISPLAY 0.680851 (2075 1725);
PAINT MONO (2075 1725);
DISPLAY INVISIBLE (2075 1725);
FORCEPROP 0 LAST CDS_SEC 1
J 0
(2075 1725);
DISPLAY 1.021277 (2075 1725);
DISPLAY INVISIBLE (2075 1725);
FORCEPROP 1 LASTPIN (1950 1900) $PN D
R 1
J 0
(1950 1893);
DISPLAY 0.659574 (1950 1893);
PAINT MONO (1950 1893);
FORCEPROP 1 LASTPIN (1800 1700) $PN G
J 2
(1810 1703);
DISPLAY 0.659574 (1810 1703);
PAINT MONO (1810 1703);
FORCEPROP 1 LASTPIN (1950 1600) $PN S
R 1
J 2
(1950 1613);
DISPLAY 0.659574 (1950 1613);
PAINT MONO (1950 1613);
FORCEPROP 1 LAST VALUE BSS138K
J 0
(2072 1571);
DISPLAY 0.723404 (2072 1571);
PAINT GREEN (2072 1571);
FORCEPROP 2 LAST MANUF_PN BSS138K
J 0
(2075 1675);
DISPLAY 1.021277 (2075 1675);
FORCEPROP 2 LAST PATH I109
J 0
(2075 1725);
DISPLAY 1.021277 (2075 1725);
FORCEPROP 1 LAST PART_NUMBER BAM138K0000
J 0
(2072 1411);
DISPLAY 0.723404 (2072 1411);
PAINT GREEN (2072 1411);
FORCEPROP 1 LAST MATERIAL IC
J 0
(2072 1331);
DISPLAY 0.723404 (2072 1331);
PAINT GREEN (2072 1331);
FORCEPROP 1 LAST PACK_TYPE SMLF
J 0
(1925 1550);
DISPLAY 0.723404 (1925 1550);
PAINT GREEN (1925 1550);
DISPLAY INVISIBLE (1925 1550);
FORCEPROP 2 LAST CDS_LIB pure_quanta
J 0
(1900 1800);
DISPLAY INVISIBLE (1900 1800);
FORCEPROP 1 LAST CDS_LMAN_SYM_OUTLINE -50,50,100,-150
J 0
(1900 1800);
DISPLAY 0.468085 (1900 1800);
PAINT GREEN (1900 1800);
DISPLAY INVISIBLE (1900 1800);
FORCEADD OFFPAGE..2
(3200 2125);
FORCEPROP 2 LAST $XR0 215 
J 0
(3389 2125);
DISPLAY 0.638298 (3389 2125);
PAINT MONO (3389 2125);
FORCEPROP 1 LAST COMMENT_BODY TRUE
J 0
(3155 2030);
DISPLAY 0.872340 (3155 2030);
PAINT GREEN (3155 2030);
DISPLAY INVISIBLE (3155 2030);
FORCEPROP 1 LAST OFFPAGE TRUE
J 0
(3525 2000);
DISPLAY 0.872340 (3525 2000);
PAINT AQUA (3525 2000);
DISPLAY INVISIBLE (3525 2000);
FORCEPROP 2 LAST CDS_LIB standard
J 0
(3200 2125);
DISPLAY INVISIBLE (3200 2125);
FORCEPROP 2 LAST PATH I110
J 0
(3400 2175);
DISPLAY 1.021277 (3400 2175);
DISPLAY INVISIBLE (3400 2175);
FORCEADD UNIVERSAL_GND..1
(1950 1425);
FORCEPROP 3 LASTPIN (1950 1475) SIG_NAME GND\g
J 0
(1960 1485);
DISPLAY 0.659574 (1960 1485);
PAINT MONO (1960 1485);
DISPLAY INVISIBLE (1960 1485);
FORCEPROP 1 LAST HDL_POWER GND
J 1
(1975 1350);
DISPLAY 0.872340 (1975 1350);
PAINT GREEN (1975 1350);
DISPLAY INVISIBLE (1975 1350);
FORCEPROP 1 LAST PATH I111
J 0
(2025 1425);
DISPLAY 0.872340 (2025 1425);
PAINT AQUA (2025 1425);
DISPLAY INVISIBLE (2025 1425);
FORCEPROP 2 LAST CDS_LIB pure_quanta_power
J 0
(1950 1425);
DISPLAY INVISIBLE (1950 1425);
FORCEADD UNIVERSAL_POWER..1
(1950 2600);
FORCEPROP 3 LASTPIN (1950 2550) SIG_NAME P3V3_AUX\g
J 0
(1960 2560);
DISPLAY 0.659574 (1960 2560);
PAINT MONO (1960 2560);
DISPLAY INVISIBLE (1960 2560);
FORCEPROP 1 LAST HDL_POWER P3V3_AUX
J 1
(1950 2650);
DISPLAY 0.723404 (1950 2650);
PAINT GREEN (1950 2650);
FORCEPROP 2 LAST CDS_LIB pure_quanta_power
J 0
(1950 2600);
DISPLAY INVISIBLE (1950 2600);
FORCEPROP 1 LAST PATH I113
J 0
(2000 2625);
DISPLAY 0.872340 (2000 2625);
PAINT AQUA (2000 2625);
DISPLAY INVISIBLE (2000 2625);
FORCEADD Q_RES..2
(1950 2375);
FORCEPROP 1 LAST $LOCATION R4620
J 0
(2005 2525);
DISPLAY 0.638298 (2005 2525);
FORCEPROP 0 LAST CDS_LOCATION R4620
J 0
(2025 2575);
DISPLAY 1.021277 (2025 2575);
DISPLAY INVISIBLE (2025 2575);
FORCEPROP 0 LAST $SEC 1
J 0
(2025 2575);
DISPLAY 0.680851 (2025 2575);
PAINT MONO (2025 2575);
DISPLAY INVISIBLE (2025 2575);
FORCEPROP 0 LAST CDS_SEC 1
J 0
(2025 2575);
DISPLAY 1.021277 (2025 2575);
DISPLAY INVISIBLE (2025 2575);
FORCEPROP 1 LASTPIN (1950 2475) $PN 1
J 0
(1955 2437);
DISPLAY 0.787234 (1955 2437);
PAINT MONO (1955 2437);
FORCEPROP 1 LASTPIN (1950 2275) $PN 2
J 0
(1955 2285);
DISPLAY 0.787234 (1955 2285);
PAINT MONO (1955 2285);
FORCEPROP 1 LAST PART_NUMBER CS24702JB10
J 0
(2000 2275);
DISPLAY 0.638298 (2000 2275);
FORCEPROP 1 LAST WATTAGE 1/16W
J 0
(2000 2375);
DISPLAY 0.638298 (2000 2375);
FORCEPROP 1 LAST TOLERANCE 5%
J 0
(2005 2425);
DISPLAY 0.638298 (2005 2425);
FORCEPROP 1 LAST VALUE 4.7K
J 0
(2005 2475);
DISPLAY 0.638298 (2005 2475);
FORCEPROP 1 LAST PACK_TYPE 0402LF
J 0
(2000 2225);
DISPLAY 0.638298 (2000 2225);
FORCEPROP 1 LAST MATERIAL CHIP
J 0
(2000 2325);
DISPLAY 0.638298 (2000 2325);
FORCEPROP 1 LAST PATH I114
J 0
(2000 2550);
DISPLAY 0.978723 (2000 2550);
PAINT WHITE (2000 2550);
DISPLAY INVISIBLE (2000 2550);
FORCEPROP 2 LAST CDS_LIB pure_quanta
J 0
(1950 2375);
DISPLAY INVISIBLE (1950 2375);
FORCEADD Q_RES..2
(-2025 2200);
FORCEPROP 1 LAST LOCATION R2221
J 0
(-1980 2325);
DISPLAY 0.723404 (-1980 2325);
PAINT AQUA (-1980 2325);
FORCEPROP 2 LAST $SEC 1
J 0
(-1975 2425);
DISPLAY 0.680851 (-1975 2425);
PAINT MONO (-1975 2425);
DISPLAY INVISIBLE (-1975 2425);
FORCEPROP 0 LAST CDS_SEC 1
J 0
(-1975 2425);
DISPLAY 0.680851 (-1975 2425);
PAINT MONO (-1975 2425);
DISPLAY INVISIBLE (-1975 2425);
FORCEPROP 1 LASTPIN (-2025 2300) $PN 1
J 0
(-2020 2262);
DISPLAY 0.723404 (-2020 2262);
PAINT MONO (-2020 2262);
FORCEPROP 1 LASTPIN (-2025 2100) $PN 2
J 0
(-2020 2110);
DISPLAY 0.723404 (-2020 2110);
PAINT MONO (-2020 2110);
FORCEPROP 1 LAST PART_NUMBER CS32672FB03
J 0
(-1985 2075);
DISPLAY 0.723404 (-1985 2075);
PAINT WHITE (-1985 2075);
FORCEPROP 1 LAST PACK_TYPE 0402LF
J 0
(-1985 2025);
DISPLAY 0.723404 (-1985 2025);
PAINT SKYBLUE (-1985 2025);
FORCEPROP 1 LAST TOLERANCE 1%
J 0
(-1980 2225);
DISPLAY 0.723404 (-1980 2225);
PAINT SKYBLUE (-1980 2225);
FORCEPROP 1 LAST WATTAGE 1/16W
J 0
(-1985 2175);
DISPLAY 0.723404 (-1985 2175);
PAINT SKYBLUE (-1985 2175);
FORCEPROP 1 LAST VALUE 26.7K
J 0
(-1980 2275);
DISPLAY 0.723404 (-1980 2275);
PAINT SKYBLUE (-1980 2275);
FORCEPROP 1 LAST MATERIAL CHIP
J 0
(-1985 2125);
DISPLAY 0.723404 (-1985 2125);
PAINT SKYBLUE (-1985 2125);
FORCEPROP 2 LAST CDS_LIB pure_quanta
J 0
(-2025 2200);
DISPLAY INVISIBLE (-2025 2200);
FORCEPROP 1 LAST PATH I23
J 0
(-1975 2375);
DISPLAY 0.978723 (-1975 2375);
PAINT WHITE (-1975 2375);
DISPLAY INVISIBLE (-1975 2375);
FORCEADD Q_RES..2
(-2625 2200);
FORCEPROP 1 LAST LOCATION R2219
J 0
(-2580 2325);
DISPLAY 0.723404 (-2580 2325);
PAINT AQUA (-2580 2325);
FORCEPROP 2 LAST $SEC 1
J 0
(-2575 2425);
DISPLAY 0.680851 (-2575 2425);
PAINT MONO (-2575 2425);
DISPLAY INVISIBLE (-2575 2425);
FORCEPROP 0 LAST CDS_SEC 1
J 0
(-2575 2425);
DISPLAY 0.680851 (-2575 2425);
PAINT MONO (-2575 2425);
DISPLAY INVISIBLE (-2575 2425);
FORCEPROP 1 LASTPIN (-2625 2300) $PN 1
J 0
(-2620 2262);
DISPLAY 0.723404 (-2620 2262);
PAINT MONO (-2620 2262);
FORCEPROP 1 LASTPIN (-2625 2100) $PN 2
J 0
(-2620 2110);
DISPLAY 0.723404 (-2620 2110);
PAINT MONO (-2620 2110);
FORCEPROP 1 LAST VALUE 267K
J 0
(-2580 2275);
DISPLAY 0.723404 (-2580 2275);
PAINT SKYBLUE (-2580 2275);
FORCEPROP 1 LAST WATTAGE 1/16W
J 0
(-2585 2175);
DISPLAY 0.723404 (-2585 2175);
PAINT SKYBLUE (-2585 2175);
FORCEPROP 1 LAST TOLERANCE 1%
J 0
(-2580 2225);
DISPLAY 0.723404 (-2580 2225);
PAINT SKYBLUE (-2580 2225);
FORCEPROP 1 LAST MATERIAL CHIP
J 0
(-2585 2125);
DISPLAY 0.723404 (-2585 2125);
PAINT SKYBLUE (-2585 2125);
FORCEPROP 1 LAST PACK_TYPE 0402LF
J 0
(-2585 2025);
DISPLAY 0.723404 (-2585 2025);
PAINT SKYBLUE (-2585 2025);
FORCEPROP 1 LAST PART_NUMBER CS42672FB03
J 0
(-2585 2075);
DISPLAY 0.723404 (-2585 2075);
PAINT WHITE (-2585 2075);
FORCEPROP 2 LAST CDS_LIB pure_quanta
J 0
(-2625 2200);
DISPLAY INVISIBLE (-2625 2200);
FORCEPROP 1 LAST PATH I3
J 0
(-2575 2375);
DISPLAY 0.978723 (-2575 2375);
PAINT WHITE (-2575 2375);
DISPLAY INVISIBLE (-2575 2375);
FORCEADD UNIVERSAL_GND..1
(200 1475);
FORCEPROP 3 LASTPIN (200 1525) SIG_NAME GND\g
J 0
(210 1535);
DISPLAY 0.659574 (210 1535);
PAINT MONO (210 1535);
DISPLAY INVISIBLE (210 1535);
FORCEPROP 1 LAST HDL_POWER GND
J 1
(225 1400);
DISPLAY 0.872340 (225 1400);
PAINT GREEN (225 1400);
DISPLAY INVISIBLE (225 1400);
FORCEPROP 2 LAST CDS_LIB pure_quanta_power
J 0
(200 1475);
DISPLAY INVISIBLE (200 1475);
FORCEPROP 1 LAST PATH I30
J 0
(275 1475);
DISPLAY 0.872340 (275 1475);
PAINT AQUA (275 1475);
DISPLAY INVISIBLE (275 1475);
FORCEADD Q_RES..2
(300 2175);
FORCEPROP 1 LAST LOCATION R2230
J 0
(345 2300);
DISPLAY 0.723404 (345 2300);
PAINT AQUA (345 2300);
FORCEPROP 2 LAST $SEC 1
J 0
(350 2400);
DISPLAY 0.680851 (350 2400);
PAINT MONO (350 2400);
DISPLAY INVISIBLE (350 2400);
FORCEPROP 2 LAST CDS_SEC 1
J 0
(350 2400);
DISPLAY 0.680851 (350 2400);
DISPLAY INVISIBLE (350 2400);
FORCEPROP 1 LASTPIN (300 2275) $PN 1
J 0
(305 2237);
DISPLAY 0.723404 (305 2237);
PAINT WHITE (305 2237);
FORCEPROP 1 LASTPIN (300 2075) $PN 2
J 0
(305 2085);
DISPLAY 0.723404 (305 2085);
PAINT WHITE (305 2085);
FORCEPROP 1 LAST VALUE 10K
J 0
(345 2250);
DISPLAY 0.723404 (345 2250);
PAINT SKYBLUE (345 2250);
FORCEPROP 1 LAST TOLERANCE 1%
J 0
(345 2200);
DISPLAY 0.723404 (345 2200);
PAINT SKYBLUE (345 2200);
FORCEPROP 1 LAST MATERIAL CHIP
J 0
(340 2100);
DISPLAY 0.723404 (340 2100);
PAINT SKYBLUE (340 2100);
FORCEPROP 1 LAST PACK_TYPE 0402LF
J 0
(350 2050);
DISPLAY 0.723404 (350 2050);
PAINT SKYBLUE (350 2050);
FORCEPROP 1 LAST WATTAGE 1/16W
J 0
(340 2150);
DISPLAY 0.723404 (340 2150);
PAINT SKYBLUE (340 2150);
FORCEPROP 1 LAST PATH I35
J 0
(350 2350);
DISPLAY 0.978723 (350 2350);
PAINT WHITE (350 2350);
DISPLAY INVISIBLE (350 2350);
FORCEPROP 2 LAST CDS_LIB pure_quanta
J 0
(300 2175);
DISPLAY INVISIBLE (300 2175);
FORCEPROP 1 LAST PART_NUMBER CS31002FB08
J 0
(340 2050);
DISPLAY 0.723404 (340 2050);
PAINT WHITE (340 2050);
DISPLAY INVISIBLE (340 2050);
FORCEADD Q_RES..2
(600 2200);
FORCEPROP 1 LAST LOCATION R2233
J 0
(645 2325);
DISPLAY 0.723404 (645 2325);
PAINT AQUA (645 2325);
FORCEPROP 2 LAST $SEC 1
J 0
(650 2425);
DISPLAY 0.680851 (650 2425);
PAINT MONO (650 2425);
DISPLAY INVISIBLE (650 2425);
FORCEPROP 2 LAST CDS_SEC 1
J 0
(650 2425);
DISPLAY 0.680851 (650 2425);
DISPLAY INVISIBLE (650 2425);
FORCEPROP 1 LASTPIN (600 2300) $PN 1
J 0
(605 2262);
DISPLAY 0.723404 (605 2262);
PAINT WHITE (605 2262);
FORCEPROP 1 LASTPIN (600 2100) $PN 2
J 0
(605 2110);
DISPLAY 0.723404 (605 2110);
PAINT WHITE (605 2110);
FORCEPROP 1 LAST VALUE 10K
J 0
(645 2275);
DISPLAY 0.723404 (645 2275);
PAINT SKYBLUE (645 2275);
FORCEPROP 1 LAST TOLERANCE 1%
J 0
(645 2225);
DISPLAY 0.723404 (645 2225);
PAINT SKYBLUE (645 2225);
FORCEPROP 1 LAST WATTAGE 1/16W
J 0
(640 2175);
DISPLAY 0.723404 (640 2175);
PAINT SKYBLUE (640 2175);
FORCEPROP 1 LAST MATERIAL CHIP
J 0
(640 2125);
DISPLAY 0.723404 (640 2125);
PAINT SKYBLUE (640 2125);
FORCEPROP 1 LAST PACK_TYPE 0402LF
J 0
(650 2075);
DISPLAY 0.723404 (650 2075);
PAINT SKYBLUE (650 2075);
FORCEPROP 1 LAST PATH I36
J 0
(650 2375);
DISPLAY 0.978723 (650 2375);
PAINT WHITE (650 2375);
DISPLAY INVISIBLE (650 2375);
FORCEPROP 2 LAST CDS_LIB pure_quanta
J 0
(600 2200);
DISPLAY INVISIBLE (600 2200);
FORCEPROP 1 LAST PART_NUMBER CS31002FB08
J 0
(640 2075);
DISPLAY 0.723404 (640 2075);
PAINT WHITE (640 2075);
DISPLAY INVISIBLE (640 2075);
FORCEADD UNIVERSAL_POWER..1
(-2625 2550);
FORCEPROP 3 LASTPIN (-2625 2500) SIG_NAME P12V_AUX\g
J 0
(-2615 2510);
DISPLAY 0.659574 (-2615 2510);
PAINT MONO (-2615 2510);
DISPLAY INVISIBLE (-2615 2510);
FORCEPROP 1 LAST HDL_POWER P12V_AUX
J 1
(-2625 2600);
DISPLAY 0.723404 (-2625 2600);
PAINT GREEN (-2625 2600);
FORCEPROP 2 LAST CDS_LIB pure_quanta_power
J 0
(-2625 2550);
PAINT MONO (-2625 2550);
DISPLAY INVISIBLE (-2625 2550);
FORCEPROP 1 LAST PATH I4
J 0
(-2575 2575);
DISPLAY 0.872340 (-2575 2575);
PAINT AQUA (-2575 2575);
DISPLAY INVISIBLE (-2575 2575);
FORCEADD UNIVERSAL_POWER..1
(-2025 2550);
FORCEPROP 3 LASTPIN (-2025 2500) SIG_NAME P12V_AUX\g
J 0
(-2015 2510);
DISPLAY 0.659574 (-2015 2510);
PAINT MONO (-2015 2510);
DISPLAY INVISIBLE (-2015 2510);
FORCEPROP 1 LAST HDL_POWER P12V_AUX
J 1
(-2025 2600);
DISPLAY 0.723404 (-2025 2600);
PAINT GREEN (-2025 2600);
FORCEPROP 2 LAST CDS_LIB pure_quanta_power
J 0
(-2025 2550);
PAINT MONO (-2025 2550);
DISPLAY INVISIBLE (-2025 2550);
FORCEPROP 1 LAST PATH I41
J 0
(-1975 2575);
DISPLAY 0.872340 (-1975 2575);
PAINT AQUA (-1975 2575);
DISPLAY INVISIBLE (-1975 2575);
FORCEADD UNIVERSAL_POWER..1
(-825 2550);
FORCEPROP 3 LASTPIN (-825 2500) SIG_NAME P12V_AUX\g
J 0
(-815 2510);
DISPLAY 0.659574 (-815 2510);
PAINT MONO (-815 2510);
DISPLAY INVISIBLE (-815 2510);
FORCEPROP 1 LAST HDL_POWER P12V_AUX
J 1
(-825 2600);
DISPLAY 0.723404 (-825 2600);
PAINT GREEN (-825 2600);
FORCEPROP 2 LAST CDS_LIB pure_quanta_power
J 0
(-825 2550);
PAINT MONO (-825 2550);
DISPLAY INVISIBLE (-825 2550);
FORCEPROP 1 LAST PATH I44
J 0
(-775 2575);
DISPLAY 0.872340 (-775 2575);
PAINT AQUA (-775 2575);
DISPLAY INVISIBLE (-775 2575);
FORCEADD UNIVERSAL_POWER..1
(300 2550);
FORCEPROP 3 LASTPIN (300 2500) SIG_NAME P3V3_AUX\g
J 0
(310 2510);
DISPLAY 0.659574 (310 2510);
PAINT MONO (310 2510);
DISPLAY INVISIBLE (310 2510);
FORCEPROP 1 LAST HDL_POWER P3V3_AUX
J 1
(300 2600);
DISPLAY 0.723404 (300 2600);
PAINT GREEN (300 2600);
FORCEPROP 2 LAST CDS_LIB pure_quanta_power
J 0
(300 2550);
PAINT MONO (300 2550);
DISPLAY INVISIBLE (300 2550);
FORCEPROP 1 LAST PATH I51
J 0
(350 2575);
DISPLAY 0.872340 (350 2575);
PAINT AQUA (350 2575);
DISPLAY INVISIBLE (350 2575);
FORCEADD OFFPAGE..2
(1475 1800);
FORCEPROP 2 LAST $XR0 215 
J 0
(1664 1800);
DISPLAY 0.638298 (1664 1800);
PAINT MONO (1664 1800);
FORCEPROP 1 LAST COMMENT_BODY TRUE
J 0
(1430 1705);
DISPLAY 0.872340 (1430 1705);
PAINT GREEN (1430 1705);
DISPLAY INVISIBLE (1430 1705);
FORCEPROP 1 LAST OFFPAGE TRUE
J 0
(1800 1675);
DISPLAY 0.872340 (1800 1675);
PAINT AQUA (1800 1675);
DISPLAY INVISIBLE (1800 1675);
FORCEPROP 2 LAST CDS_LIB standard
J 0
(1475 1800);
DISPLAY INVISIBLE (1475 1800);
FORCEPROP 2 LAST PATH I62
J 0
(1675 1850);
DISPLAY 1.021277 (1675 1850);
DISPLAY INVISIBLE (1675 1850);
FORCEADD LT6700CS61TRPBF..1
(-250 1750);
FORCEPROP 1 LAST $LOCATION U206
J 0
(-469 2181);
DISPLAY 0.723404 (-469 2181);
PAINT GREEN (-469 2181);
FORCEPROP 0 LAST CDS_LOCATION U206
J 0
(-475 2300);
DISPLAY 1.021277 (-475 2300);
DISPLAY INVISIBLE (-475 2300);
FORCEPROP 0 LAST $SEC 1
J 0
(-475 2300);
DISPLAY 0.680851 (-475 2300);
PAINT MONO (-475 2300);
DISPLAY INVISIBLE (-475 2300);
FORCEPROP 0 LAST CDS_SEC 1
J 0
(-475 2300);
DISPLAY 1.021277 (-475 2300);
DISPLAY INVISIBLE (-475 2300);
FORCEPROP 0 LASTPIN (125 1650) $PN 2
J 0
(135 1660);
DISPLAY 0.680851 (135 1660);
PAINT MONO (135 1660);
FORCEPROP 0 LASTPIN (-625 1800) $PN 3
J 2
(-635 1810);
DISPLAY 0.680851 (-635 1810);
PAINT MONO (-635 1810);
FORCEPROP 0 LASTPIN (-625 1700) $PN 4
J 2
(-635 1710);
DISPLAY 0.680851 (-635 1710);
PAINT MONO (-635 1710);
FORCEPROP 0 LASTPIN (125 1800) $PN 1
J 0
(135 1810);
DISPLAY 0.680851 (135 1810);
PAINT MONO (135 1810);
FORCEPROP 0 LASTPIN (125 1700) $PN 6
J 0
(135 1710);
DISPLAY 0.680851 (135 1710);
PAINT MONO (135 1710);
FORCEPROP 0 LASTPIN (-625 1850) $PN 5
J 2
(-635 1860);
DISPLAY 0.680851 (-635 1860);
PAINT MONO (-635 1860);
FORCEPROP 2 LAST PART_TYPE SMLF
J 0
(-475 2250);
DISPLAY 1.021277 (-475 2250);
FORCEPROP 2 LAST VALUE LT6700CS6-1#TRPBF
J 0
(-650 2075);
DISPLAY 1.021277 (-650 2075);
FORCEPROP 1 LAST PART_NUMBER AL006700001
J 0
(-469 2034);
DISPLAY 0.723404 (-469 2034);
PAINT GREEN (-469 2034);
FORCEPROP 1 LAST MATERIAL IC
J 0
(-469 1907);
DISPLAY 0.723404 (-469 1907);
PAINT GREEN (-469 1907);
FORCEPROP 2 LAST CDS_LIB pure_quanta
J 0
(-250 1750);
DISPLAY INVISIBLE (-250 1750);
FORCEPROP 1 LAST CDS_LMAN_SYM_OUTLINE -225,150,225,-150
J 0
(-250 1750);
DISPLAY 0.468085 (-250 1750);
PAINT GREEN (-250 1750);
DISPLAY INVISIBLE (-250 1750);
FORCEPROP 1 LAST NEEDS_NO_SIZE TRUE
J 0
(-250 1750);
DISPLAY 0.723404 (-250 1750);
PAINT GREEN (-250 1750);
DISPLAY INVISIBLE (-250 1750);
FORCEPROP 1 LAST PATH I75
J 0
(-250 1750);
DISPLAY 0.723404 (-250 1750);
PAINT GREEN (-250 1750);
DISPLAY INVISIBLE (-250 1750);
FORCEADD Q_RES..2
(-2625 1450);
FORCEPROP 1 LAST LOCATION R2227
J 0
(-2580 1575);
DISPLAY 0.638298 (-2580 1575);
FORCEPROP 0 LAST $SEC 1
J 0
(-2575 1625);
DISPLAY 0.680851 (-2575 1625);
PAINT MONO (-2575 1625);
DISPLAY INVISIBLE (-2575 1625);
FORCEPROP 2 LAST CDS_SEC 1
J 0
(-2575 1675);
DISPLAY 0.680851 (-2575 1675);
DISPLAY INVISIBLE (-2575 1675);
FORCEPROP 1 LASTPIN (-2625 1550) $PN 1
J 0
(-2620 1512);
DISPLAY 0.787234 (-2620 1512);
PAINT MONO (-2620 1512);
FORCEPROP 1 LASTPIN (-2625 1350) $PN 2
J 0
(-2620 1360);
DISPLAY 0.787234 (-2620 1360);
PAINT MONO (-2620 1360);
FORCEPROP 1 LAST TOLERANCE 1%
J 0
(-2580 1475);
DISPLAY 0.638298 (-2580 1475);
FORCEPROP 1 LAST VALUE 10K
J 0
(-2580 1525);
DISPLAY 0.638298 (-2580 1525);
FORCEPROP 1 LAST PACK_TYPE 0402LF
J 0
(-2585 1275);
DISPLAY 0.638298 (-2585 1275);
FORCEPROP 1 LAST WATTAGE 1/16W
J 0
(-2585 1425);
DISPLAY 0.638298 (-2585 1425);
FORCEPROP 1 LAST MATERIAL CHIP
J 0
(-2585 1375);
DISPLAY 0.638298 (-2585 1375);
FORCEPROP 1 LAST PART_NUMBER CS31002FB08
J 0
(-2585 1325);
DISPLAY 0.638298 (-2585 1325);
FORCEPROP 1 LAST PATH I83
J 0
(-2575 1625);
DISPLAY 0.978723 (-2575 1625);
PAINT WHITE (-2575 1625);
DISPLAY INVISIBLE (-2575 1625);
FORCEPROP 2 LAST CDS_LIB pure_quanta
J 0
(-2625 1450);
DISPLAY INVISIBLE (-2625 1450);
FORCEADD Q_RES..2
(-2025 1450);
FORCEPROP 1 LAST LOCATION R2222
J 0
(-1980 1575);
DISPLAY 0.723404 (-1980 1575);
PAINT AQUA (-1980 1575);
FORCEPROP 2 LAST $SEC 1
J 0
(-1975 1675);
DISPLAY 0.680851 (-1975 1675);
PAINT MONO (-1975 1675);
DISPLAY INVISIBLE (-1975 1675);
FORCEPROP 0 LAST CDS_SEC 1
J 0
(-1975 1675);
DISPLAY 0.680851 (-1975 1675);
PAINT MONO (-1975 1675);
DISPLAY INVISIBLE (-1975 1675);
FORCEPROP 1 LASTPIN (-2025 1550) $PN 1
J 0
(-2020 1512);
DISPLAY 0.723404 (-2020 1512);
PAINT MONO (-2020 1512);
FORCEPROP 1 LASTPIN (-2025 1350) $PN 2
J 0
(-2020 1360);
DISPLAY 0.723404 (-2020 1360);
PAINT MONO (-2020 1360);
FORCEPROP 1 LAST TOLERANCE 1%
J 0
(-1980 1475);
DISPLAY 0.723404 (-1980 1475);
PAINT SKYBLUE (-1980 1475);
FORCEPROP 1 LAST VALUE 1K
J 0
(-1980 1525);
DISPLAY 0.723404 (-1980 1525);
PAINT SKYBLUE (-1980 1525);
FORCEPROP 1 LAST MATERIAL CHIP
J 0
(-1985 1375);
DISPLAY 0.723404 (-1985 1375);
PAINT SKYBLUE (-1985 1375);
FORCEPROP 1 LAST PACK_TYPE 0402LF
J 0
(-1985 1275);
DISPLAY 0.723404 (-1985 1275);
PAINT SKYBLUE (-1985 1275);
FORCEPROP 1 LAST PART_NUMBER CS21002FB06
J 0
(-1985 1325);
DISPLAY 0.723404 (-1985 1325);
PAINT WHITE (-1985 1325);
FORCEPROP 1 LAST WATTAGE 1/16W
J 0
(-1985 1425);
DISPLAY 0.723404 (-1985 1425);
PAINT SKYBLUE (-1985 1425);
FORCEPROP 1 LAST PATH I84
J 0
(-1975 1625);
DISPLAY 0.978723 (-1975 1625);
PAINT WHITE (-1975 1625);
DISPLAY INVISIBLE (-1975 1625);
FORCEPROP 2 LAST CDS_LIB pure_quanta
J 0
(-2025 1450);
DISPLAY INVISIBLE (-2025 1450);
FORCEADD LT6700CS61TRPBF..1
(-650 -400);
FORCEPROP 1 LAST $LOCATION U205
J 0
(-869 31);
DISPLAY 0.723404 (-869 31);
PAINT GREEN (-869 31);
FORCEPROP 0 LAST CDS_LOCATION U205
J 0
(-875 150);
DISPLAY 1.021277 (-875 150);
DISPLAY INVISIBLE (-875 150);
FORCEPROP 0 LAST $SEC 1
J 0
(-875 150);
DISPLAY 0.680851 (-875 150);
PAINT MONO (-875 150);
DISPLAY INVISIBLE (-875 150);
FORCEPROP 0 LAST CDS_SEC 1
J 0
(-875 150);
DISPLAY 1.021277 (-875 150);
DISPLAY INVISIBLE (-875 150);
FORCEPROP 0 LASTPIN (-275 -500) $PN 2
J 0
(-265 -490);
DISPLAY 0.680851 (-265 -490);
PAINT MONO (-265 -490);
FORCEPROP 0 LASTPIN (-1025 -350) $PN 3
J 2
(-1035 -340);
DISPLAY 0.680851 (-1035 -340);
PAINT MONO (-1035 -340);
FORCEPROP 0 LASTPIN (-1025 -450) $PN 4
J 2
(-1035 -440);
DISPLAY 0.680851 (-1035 -440);
PAINT MONO (-1035 -440);
FORCEPROP 0 LASTPIN (-275 -350) $PN 1
J 0
(-265 -340);
DISPLAY 0.680851 (-265 -340);
PAINT MONO (-265 -340);
FORCEPROP 0 LASTPIN (-275 -450) $PN 6
J 0
(-265 -440);
DISPLAY 0.680851 (-265 -440);
PAINT MONO (-265 -440);
FORCEPROP 0 LASTPIN (-1025 -300) $PN 5
J 2
(-1035 -290);
DISPLAY 0.680851 (-1035 -290);
PAINT MONO (-1035 -290);
FORCEPROP 1 LAST PART_NUMBER AL006700001
J 0
(-869 -116);
DISPLAY 0.723404 (-869 -116);
PAINT GREEN (-869 -116);
FORCEPROP 1 LAST MATERIAL IC
J 0
(-869 -243);
DISPLAY 0.723404 (-869 -243);
PAINT GREEN (-869 -243);
FORCEPROP 2 LAST PART_TYPE SMLF
J 0
(-875 100);
DISPLAY 1.021277 (-875 100);
FORCEPROP 2 LAST VALUE LT6700CS6-1#TRPBF
J 0
(-1050 -75);
DISPLAY 1.021277 (-1050 -75);
FORCEPROP 1 LAST NEEDS_NO_SIZE TRUE
J 0
(-650 -400);
DISPLAY 0.723404 (-650 -400);
PAINT GREEN (-650 -400);
DISPLAY INVISIBLE (-650 -400);
FORCEPROP 1 LAST CDS_LMAN_SYM_OUTLINE -225,150,225,-150
J 0
(-650 -400);
DISPLAY 0.468085 (-650 -400);
PAINT GREEN (-650 -400);
DISPLAY INVISIBLE (-650 -400);
FORCEPROP 2 LAST CDS_LIB pure_quanta
J 0
(-650 -400);
DISPLAY INVISIBLE (-650 -400);
FORCEPROP 1 LAST PATH I85
J 0
(-650 -400);
DISPLAY 0.723404 (-650 -400);
PAINT GREEN (-650 -400);
DISPLAY INVISIBLE (-650 -400);
FORCEADD UNIVERSAL_GND..1
(-200 -625);
FORCEPROP 3 LASTPIN (-200 -575) SIG_NAME GND\g
J 0
(-190 -565);
DISPLAY 0.659574 (-190 -565);
PAINT MONO (-190 -565);
DISPLAY INVISIBLE (-190 -565);
FORCEPROP 2 LAST CDS_LIB pure_quanta_power
J 0
(-200 -625);
DISPLAY INVISIBLE (-200 -625);
FORCEPROP 1 LAST PATH I90
J 0
(-125 -625);
DISPLAY 0.872340 (-125 -625);
PAINT AQUA (-125 -625);
DISPLAY INVISIBLE (-125 -625);
FORCEPROP 1 LAST HDL_POWER GND
J 1
(-175 -700);
DISPLAY 0.872340 (-175 -700);
PAINT GREEN (-175 -700);
DISPLAY INVISIBLE (-175 -700);
FORCEADD UNIVERSAL_GND..1
(-1725 -250);
FORCEPROP 3 LASTPIN (-1725 -200) SIG_NAME GND\g
J 0
(-1715 -190);
DISPLAY 0.659574 (-1715 -190);
PAINT MONO (-1715 -190);
DISPLAY INVISIBLE (-1715 -190);
FORCEPROP 1 LAST HDL_POWER GND
J 1
(-1700 -325);
DISPLAY 0.872340 (-1700 -325);
PAINT GREEN (-1700 -325);
DISPLAY INVISIBLE (-1700 -325);
FORCEPROP 1 LAST PATH I91
J 0
(-1650 -250);
DISPLAY 0.872340 (-1650 -250);
PAINT AQUA (-1650 -250);
DISPLAY INVISIBLE (-1650 -250);
FORCEPROP 2 LAST CDS_LIB pure_quanta_power
J 0
(-1725 -250);
DISPLAY INVISIBLE (-1725 -250);
FORCEADD UNIVERSAL_POWER..1
(-1225 350);
FORCEPROP 3 LASTPIN (-1225 300) SIG_NAME P3V3_AUX\g
J 0
(-1215 310);
DISPLAY 0.659574 (-1215 310);
PAINT MONO (-1215 310);
DISPLAY INVISIBLE (-1215 310);
FORCEPROP 1 LAST HDL_POWER P3V3_AUX
J 1
(-1225 400);
DISPLAY 0.723404 (-1225 400);
PAINT GREEN (-1225 400);
FORCEPROP 1 LAST PATH I93
J 0
(-1175 375);
DISPLAY 0.872340 (-1175 375);
PAINT AQUA (-1175 375);
DISPLAY INVISIBLE (-1175 375);
FORCEPROP 2 LAST CDS_LIB pure_quanta_power
J 0
(-1225 350);
PAINT MONO (-1225 350);
DISPLAY INVISIBLE (-1225 350);
FORCEADD Q_RES..2
(-2500 -250);
FORCEPROP 1 LAST $LOCATION R2238
J 0
(-2455 -125);
DISPLAY 0.638298 (-2455 -125);
FORCEPROP 0 LAST CDS_LOCATION R2238
J 0
(-2450 -75);
DISPLAY 1.021277 (-2450 -75);
DISPLAY INVISIBLE (-2450 -75);
FORCEPROP 0 LAST $SEC 1
J 0
(-2450 -75);
DISPLAY 0.680851 (-2450 -75);
PAINT MONO (-2450 -75);
DISPLAY INVISIBLE (-2450 -75);
FORCEPROP 0 LAST CDS_SEC 1
J 0
(-2450 -75);
DISPLAY INVISIBLE (-2450 -75);
FORCEPROP 1 LASTPIN (-2500 -150) $PN 1
J 0
(-2495 -188);
DISPLAY 0.787234 (-2495 -188);
PAINT MONO (-2495 -188);
FORCEPROP 1 LASTPIN (-2500 -350) $PN 2
J 0
(-2495 -340);
DISPLAY 0.787234 (-2495 -340);
PAINT MONO (-2495 -340);
FORCEPROP 1 LAST TOLERANCE 1%
J 0
(-2455 -225);
DISPLAY 0.638298 (-2455 -225);
FORCEPROP 1 LAST VALUE 4.99K
J 0
(-2455 -175);
DISPLAY 0.638298 (-2455 -175);
FORCEPROP 1 LAST PACK_TYPE 0402LF
J 0
(-2460 -425);
DISPLAY 0.638298 (-2460 -425);
FORCEPROP 1 LAST PART_NUMBER CS24992FB07
J 0
(-2460 -375);
DISPLAY 0.638298 (-2460 -375);
FORCEPROP 1 LAST MATERIAL CHIP
J 0
(-2460 -325);
DISPLAY 0.638298 (-2460 -325);
FORCEPROP 1 LAST WATTAGE 1/16W
J 0
(-2460 -275);
DISPLAY 0.638298 (-2460 -275);
FORCEPROP 1 LAST PATH I95
J 0
(-2450 -75);
DISPLAY 0.978723 (-2450 -75);
PAINT WHITE (-2450 -75);
DISPLAY INVISIBLE (-2450 -75);
FORCEPROP 2 LAST CDS_LIB pure_quanta
J 0
(-2500 -250);
DISPLAY INVISIBLE (-2500 -250);
FORCEADD Q_RES..2
(-2500 150);
FORCEPROP 1 LAST LOCATION R2236
J 0
(-2455 275);
DISPLAY 0.723404 (-2455 275);
PAINT AQUA (-2455 275);
FORCEPROP 2 LAST $SEC 1
J 0
(-2450 375);
DISPLAY 0.680851 (-2450 375);
PAINT MONO (-2450 375);
DISPLAY INVISIBLE (-2450 375);
FORCEPROP 0 LAST CDS_SEC 1
J 0
(-2450 375);
DISPLAY 0.680851 (-2450 375);
PAINT MONO (-2450 375);
DISPLAY INVISIBLE (-2450 375);
FORCEPROP 1 LASTPIN (-2500 250) $PN 1
J 0
(-2495 212);
DISPLAY 0.723404 (-2495 212);
PAINT MONO (-2495 212);
FORCEPROP 1 LASTPIN (-2500 50) $PN 2
J 0
(-2495 60);
DISPLAY 0.723404 (-2495 60);
PAINT MONO (-2495 60);
FORCEPROP 1 LAST MATERIAL CHIP
J 0
(-2460 75);
DISPLAY 0.723404 (-2460 75);
PAINT SKYBLUE (-2460 75);
FORCEPROP 1 LAST TOLERANCE 1%
J 0
(-2455 175);
DISPLAY 0.723404 (-2455 175);
PAINT SKYBLUE (-2455 175);
FORCEPROP 1 LAST WATTAGE 1/16W
J 0
(-2460 125);
DISPLAY 0.723404 (-2460 125);
PAINT SKYBLUE (-2460 125);
FORCEPROP 1 LAST PACK_TYPE 0402LF
J 0
(-2460 -25);
DISPLAY 0.723404 (-2460 -25);
PAINT SKYBLUE (-2460 -25);
FORCEPROP 1 LAST PART_NUMBER CS41002FB09
J 0
(-2460 25);
DISPLAY 0.723404 (-2460 25);
PAINT WHITE (-2460 25);
FORCEPROP 1 LAST VALUE 100K
J 0
(-2455 225);
DISPLAY 0.723404 (-2455 225);
PAINT SKYBLUE (-2455 225);
FORCEPROP 1 LAST PATH I96
J 0
(-2450 325);
DISPLAY 0.978723 (-2450 325);
PAINT WHITE (-2450 325);
DISPLAY INVISIBLE (-2450 325);
FORCEPROP 2 LAST CDS_LIB pure_quanta
J 0
(-2500 150);
PAINT MONO (-2500 150);
DISPLAY INVISIBLE (-2500 150);
FORCEADD UNIVERSAL_POWER..1
(-2500 400);
FORCEPROP 3 LASTPIN (-2500 350) SIG_NAME P12V_AUX\g
J 0
(-2490 360);
DISPLAY 0.659574 (-2490 360);
PAINT MONO (-2490 360);
DISPLAY INVISIBLE (-2490 360);
FORCEPROP 1 LAST HDL_POWER P12V_AUX
J 1
(-2500 450);
DISPLAY 0.723404 (-2500 450);
PAINT GREEN (-2500 450);
FORCEPROP 1 LAST PATH I97
J 0
(-2450 425);
DISPLAY 0.872340 (-2450 425);
PAINT AQUA (-2450 425);
DISPLAY INVISIBLE (-2450 425);
FORCEPROP 2 LAST CDS_LIB pure_quanta_power
J 0
(-2500 400);
PAINT MONO (-2500 400);
DISPLAY INVISIBLE (-2500 400);
FORCEADD OFFPAGE..2
(2150 -350);
PAINT AQUA (2150 -350);
FORCEPROP 2 LAST $XR2 214 
J 0
(2579 -350);
DISPLAY 0.638298 (2579 -350);
PAINT MONO (2579 -350);
FORCEPROP 2 LAST $XR1 182 
J 0
(2459 -350);
DISPLAY 0.638298 (2459 -350);
PAINT MONO (2459 -350);
FORCEPROP 2 LAST $XR0 244 
J 0
(2339 -350);
DISPLAY 0.638298 (2339 -350);
PAINT MONO (2339 -350);
FORCEPROP 2 LAST PATH I98
J 0
(2700 -300);
DISPLAY 1.021277 (2700 -300);
DISPLAY INVISIBLE (2700 -300);
FORCEPROP 2 LAST CDS_LIB standard
J 0
(2150 -350);
DISPLAY INVISIBLE (2150 -350);
FORCEPROP 1 LAST OFFPAGE TRUE
J 0
(2475 -475);
DISPLAY 0.872340 (2475 -475);
PAINT AQUA (2475 -475);
DISPLAY INVISIBLE (2475 -475);
FORCEPROP 1 LAST COMMENT_BODY TRUE
J 0
(2105 -445);
DISPLAY 0.872340 (2105 -445);
PAINT GREEN (2105 -445);
DISPLAY INVISIBLE (2105 -445);
FORCEADD Q_RES..1
(1000 -350);
FORCEPROP 1 LAST LOCATION R2330
J 0
(775 -325);
DISPLAY 0.723404 (775 -325);
PAINT AQUA (775 -325);
FORCEPROP 0 LAST $SEC 1
J 0
(775 -275);
DISPLAY INVISIBLE (775 -275);
FORCEPROP 2 LAST CDS_SEC 1
J 0
(950 -150);
DISPLAY 0.680851 (950 -150);
DISPLAY INVISIBLE (950 -150);
FORCEPROP 1 LASTPIN (900 -350) $PN 1
J 0
(912 -338);
DISPLAY 0.787234 (912 -338);
PAINT MONO (912 -338);
DISPLAY INVISIBLE (912 -338);
FORCEPROP 1 LASTPIN (1100 -350) $PN 2
J 0
(1062 -338);
DISPLAY 0.787234 (1062 -338);
PAINT MONO (1062 -338);
DISPLAY INVISIBLE (1062 -338);
FORCEPROP 1 LAST WATTAGE 1/16W
J 2
(1050 -275);
DISPLAY 0.723404 (1050 -275);
PAINT SKYBLUE (1050 -275);
FORCEPROP 1 LAST VALUE 0
J 2
(1100 -325);
DISPLAY 0.723404 (1100 -325);
PAINT SKYBLUE (1100 -325);
FORCEPROP 1 LAST TOLERANCE 5%
J 0
(800 -275);
DISPLAY 0.723404 (800 -275);
PAINT SKYBLUE (800 -275);
FORCEPROP 1 LAST MATERIAL EMPTY
J 0
(1125 -325);
DISPLAY 0.723404 (1125 -325);
PAINT RED (1125 -325);
FORCEPROP 1 LAST PART_NUMBER CS00002JB13
J 0
(825 -225);
DISPLAY 0.723404 (825 -225);
PAINT WHITE (825 -225);
FORCEPROP 1 LAST PACK_TYPE 0402LF
J 0
(1100 -275);
DISPLAY 0.723404 (1100 -275);
PAINT SKYBLUE (1100 -275);
FORCEPROP 1 LAST PATH I99
J 0
(950 -200);
DISPLAY 0.978723 (950 -200);
PAINT WHITE (950 -200);
DISPLAY INVISIBLE (950 -200);
FORCEPROP 2 LAST CDS_LIB pure_quanta
J 0
(1000 -350);
DISPLAY INVISIBLE (1000 -350);
FORCEADD DNS..1
(1000 -375);
PAINT RED (1000 -375);
FORCEPROP 1 LAST COMMENT_BODY TRUE
R 1
J 0
(1075 -600);
DISPLAY 0.872340 (1075 -600);
PAINT GREEN (1075 -600);
DISPLAY INVISIBLE (1075 -600);
FORCEPROP 2 LAST CDS_LIB mstr_misc
J 0
(1000 -375);
DISPLAY 0.808511 (1000 -375);
DISPLAY INVISIBLE (1000 -375);
FORCEADD QUANTA_TITLE_BLOCK_C..1
(5475 -1700);
FORCEPROP 0 LAST CDS_CON_LAST_MODIFIED Fri Mar 11 14:53:41 2022
J 0
(3590 -1685);
PAINT MONO (3590 -1685);
DISPLAY INVISIBLE (3590 -1685);
FORCEPROP 1 LAST CUSTOM_TXT_CDS <CON_LAST_MODIFIED>
J 0
(3590 -1685);
DISPLAY 0.978723 (3590 -1685);
FORCEPROP 2 LAST CUSTOM_TXT_CDS <XR_PAGE_TITLE>
J 0
(-2415 3550);
DISPLAY 0.638298 (-2415 3550);
PAINT PINK (-2415 3550);
DISPLAY INVISIBLE (-2415 3550);
FORCEPROP 1 LAST CUSTOM_TXT_CDS <NAME_2>
J 0
(2300 -1650);
FORCEPROP 1 LAST CUSTOM_TXT_CDS <NAME_1>
J 0
(2300 -1525);
FORCEPROP 1 LAST CUSTOM_TXT_CDS <Q_NUMBER>
J 0
(4072 -1597);
DISPLAY 1.212766 (4072 -1597);
FORCEPROP 1 LAST CUSTOM_TXT_CDS <Q_PROJ>
J 0
(3093 -1598);
DISPLAY 1.212766 (3093 -1598);
FORCEPROP 1 LAST CUSTOM_TXT_CDS <Q_REV>
J 0
(5291 -1597);
DISPLAY 1.212766 (5291 -1597);
FORCEPROP 1 LAST CUSTOM_TXT_CDS <CON_PAGE_NUM> OF <CON_TOTAL_PAGES>
J 0
(5029 -1682);
DISPLAY 0.978723 (5029 -1682);
FORCEPROP 1 LAST Q_TITLE HSC MP5990 (4/4)
J 0
(-3891 -1674);
DISPLAY 2.446809 (-3891 -1674);
PAINT GREEN (-3891 -1674);
FORCEPROP 1 LAST Q_DEPT BU9
J 1
(1712 -1651);
DISPLAY 1.957447 (1712 -1651);
PAINT GREEN (1712 -1651);
FORCEPROP 1 LAST COMMENT_BODY TRUE
J 0
(5487 -1713);
DISPLAY 0.978723 (5487 -1713);
PAINT GREEN (5487 -1713);
DISPLAY INVISIBLE (5487 -1713);
FORCEPROP 2 LAST PAGE_BORDER TRUE
J 0
(-2415 3550);
DISPLAY 0.638298 (-2415 3550);
PAINT PINK (-2415 3550);
DISPLAY INVISIBLE (-2415 3550);
FORCEPROP 1 LAST CDS_LMAN_SYM_OUTLINE -9475,6775,100,-125
J 0
(5475 -1700);
DISPLAY 0.468085 (5475 -1700);
PAINT GREEN (5475 -1700);
DISPLAY INVISIBLE (5475 -1700);
FORCEPROP 2 LAST CDS_LIB pure_quanta
J 0
(5475 -1700);
PAINT MONO (5475 -1700);
DISPLAY INVISIBLE (5475 -1700);
FORCEPROP 2 LAST CDS_XR_PAGE_TITLE CR-304 : @S9S_MB_2U_LIB.S9S_MB_2U(SCH_1):PAGE304
J 0
(-2415 3550);
DISPLAY 0.638298 (-2415 3550);
PAINT PINK (-2415 3550);
DISPLAY INVISIBLE (-2415 3550);
WIRE 16 -1 (-2500 -350)(-2500 -450);
WIRE 16 -1 (-2625 1350)(-2625 1200);
WIRE 16 -1 (-2025 1350)(-2025 1200);
WIRE 16 -1 (-1325 2100)(-1325 2000);
WIRE 16 -1 (1950 1475)(1950 1600);
WIRE 16 -1 (1950 2475)(1950 2550);
WIRE 16 -1 (-2625 2500)(-2625 2300);
WIRE 16 -1 (-2025 2500)(-2025 2300);
WIRE 16 -1 (-1725 -100)(-1725 -200);
WIRE 16 -1 (-2500 250)(-2500 350);
WIRE 16 -1 (2100 -350)(1100 -350);
FORCEPROP 2 LAST SIG_NAME PWRGD_DSW_PWROK
J 0
(1440 -340);
DISPLAY 0.723404 (1440 -340);
WIRE 16 2175 (-2625 -675)(-2325 -675);
WIRE 16 2175 (-2625 -425)(-2625 -675);
WIRE 16 2175 (-2325 -425)(-2325 -675);
WIRE 16 2175 (-2625 -425)(-2325 -425);
WIRE 16 -1 (600 -450)(-275 -450);
FORCEPROP 2 LAST SIG_NAME NC_U205_OUTB
J 0
(-60 -440);
DISPLAY 0.723404 (-60 -440);
WIRE 16 -1 (900 -350)(-275 -350);
FORCEPROP 2 LAST SIG_NAME PWRGD_DSW_PWROK_R4
J 0
(-60 -340);
DISPLAY 0.723404 (-60 -340);
WIRE 16 -1 (-1025 -450)(-1900 -450);
FORCEPROP 2 LAST SIG_NAME NC_U205_INB-
J 0
(-1560 -440);
DISPLAY 0.723404 (-1560 -440);
WIRE 16 -1 (-2500 50)(-2500 -50);
WIRE 16 -1 (-1900 -50)(-2500 -50);
WIRE 16 -1 (-2500 -50)(-2500 -150);
WIRE 16 -1 (-1900 -350)(-1900 -50);
WIRE 16 -1 (-1025 -350)(-1900 -350);
FORCEPROP 2 LAST SIG_NAME A_HSC_INAP
J 0
(-1560 -340);
DISPLAY 0.723404 (-1560 -340);
WIRE 16 2175 (-2750 1100)(-1825 1100);
WIRE 16 2175 (-2750 1250)(-2750 1100);
WIRE 16 2175 (-1825 1250)(-1825 1100);
WIRE 16 2175 (-2750 1250)(-1825 1250);
WIRE 16 -1 (-2025 1550)(-2025 1700);
WIRE 16 -1 (-2025 2100)(-2025 1700);
WIRE 16 -1 (-625 1700)(-2025 1700);
FORCEPROP 2 LAST SIG_NAME A_P12V_STBY_FP_TRIGGER
J 0
(-1885 1710);
DISPLAY 0.723404 (-1885 1710);
WIRE 16 -1 (1950 1900)(1950 2125);
WIRE 16 -1 (1950 2125)(3150 2125);
FORCEPROP 2 LAST SIG_NAME IRQ_UV_DETECT_N
J 0
(2390 2135);
DISPLAY 0.723404 (2390 2135);
WIRE 16 -1 (1950 2125)(1950 2275);
WIRE 16 -1 (125 1700)(300 1700);
WIRE 16 -1 (300 2075)(300 1700);
WIRE 16 -1 (1800 1700)(300 1700);
FORCEPROP 2 LAST SIG_NAME A_P12V_STBY_FPH_GATE
J 0
(640 1710);
DISPLAY 0.723404 (640 1710);
WIRE 16 -1 (600 1800)(600 2100);
WIRE 16 -1 (600 1800)(1425 1800);
FORCEPROP 2 LAST SIG_NAME FM_UV_ADR_TRIGGER_N
J 0
(665 1810);
DISPLAY 0.723404 (665 1810);
WIRE 16 -1 (600 1800)(125 1800);
WIRE 16 -1 (-2625 1550)(-2625 1800);
WIRE 16 -1 (-625 1800)(-2625 1800);
FORCEPROP 2 LAST SIG_NAME A_P12V_STBY_ADR_TRIGGER
J 0
(-1885 1810);
DISPLAY 0.723404 (-1885 1810);
WIRE 16 -1 (-2625 1800)(-2625 2100);
WIRE 16 -1 (-1325 2300)(-1325 2400);
WIRE 16 -1 (-1325 2400)(-825 2400);
WIRE 16 -1 (-825 2500)(-825 2400);
WIRE 16 -1 (-825 1850)(-825 2400);
WIRE 16 -1 (-825 1850)(-625 1850);
WIRE 16 -1 (200 1525)(200 1650);
WIRE 16 -1 (200 1650)(125 1650);
WIRE 16 -1 (300 2400)(600 2400);
WIRE 16 -1 (300 2400)(300 2500);
WIRE 16 -1 (300 2275)(300 2400);
WIRE 16 -1 (600 2400)(600 2300);
WIRE 16 -1 (-200 -575)(-200 -500);
WIRE 16 -1 (-200 -500)(-275 -500);
WIRE 16 -1 (-1225 -300)(-1225 200);
WIRE 16 -1 (-1225 -300)(-1025 -300);
WIRE 16 -1 (-1225 300)(-1225 200);
WIRE 16 -1 (-1725 200)(-1225 200);
WIRE 16 -1 (-1725 100)(-1725 200);
DOT 1 (1950 2125);
DOT 1 (300 1700);
DOT 1 (-1225 200);
DOT 1 (-2025 1700);
DOT 1 (600 1800);
DOT 1 (-2625 1800);
DOT 1 (300 2400);
DOT 1 (-825 2400);
DOT 1 (-2500 -50);
FORCENOTE
NOTE:NEED TO SET UV VOL
(-3125 925) 0;
DISPLAY LEFT (-3125 925);
DISPLAY 1.595745 (-3125 925);
PAINT WHITE (-3125 925);
FORCENOTE
20210705 MODIFY FOR GT
(2850 4750) 0;
DISPLAY LEFT (2850 4750);
DISPLAY 2.510638 (2850 4750);
PAINT PINK (2850 4750);
QUIT
